(kicad_pcb
	(version 20260206)
	(generator "pcbnew")
	(generator_version "10.0")
	(general
		(thickness 1.6)
		(legacy_teardrops no)
	)
	(paper "A4")
	(title_block
		(title "01162023_DA0F0TEBIF0_F0T_Expander_BD_F_brd_V02_OCP.brd")
		(comment 1 "Grand Teton / footprint 2305 of 9728 (J3), pads 77-130 of 130")
	)
	(layers
		(0 "F.Cu" signal "TOP")
		(4 "In1.Cu" signal "GND")
		(6 "In2.Cu" signal "VCC")
		(8 "In3.Cu" signal "VCC1")
		(10 "In4.Cu" signal "GND1")
		(12 "In5.Cu" signal "IN1")
		(14 "In6.Cu" signal "GND2")
		(16 "In7.Cu" signal "IN2")
		(18 "In8.Cu" signal "GND3")
		(20 "In9.Cu" signal "IN3")
		(22 "In10.Cu" signal "GND4")
		(24 "In11.Cu" signal "IN4")
		(26 "In12.Cu" signal "GND5")
		(28 "In13.Cu" signal "IN5")
		(30 "In14.Cu" signal "GND6")
		(32 "In15.Cu" signal "IN6")
		(34 "In16.Cu" signal "GND7")
		(2 "B.Cu" signal "BOTTOM")
		(9 "F.Adhes" user "F.Adhesive")
		(11 "B.Adhes" user "B.Adhesive")
		(13 "F.Paste" user "Package Geometry/Pastemask Top")
		(15 "B.Paste" user "Package Geometry/Pastemask Bottom")
		(5 "F.SilkS" user "Ref Des/Silkscreen Top")
		(7 "B.SilkS" user "Ref Des/Silkscreen Bottom")
		(1 "F.Mask" user "Board Geometry/Soldermask Top")
		(3 "B.Mask" user "Board Geometry/Soldermask Bottom")
		(17 "Dwgs.User" user "User.Drawings")
		(19 "Cmts.User" user "User.Comments")
		(21 "Eco1.User" user "User.Eco1")
		(23 "Eco2.User" user "User.Eco2")
		(25 "Edge.Cuts" user "Board Geometry/Outline")
		(27 "Margin" user)
		(31 "F.CrtYd" user "Package Geometry/Place Bound Top")
		(29 "B.CrtYd" user "Package Geometry/Place Bound Bottom")
		(35 "F.Fab" user "Ref Des/Assembly Top")
		(33 "B.Fab" user "Ref Des/Assembly Bottom")
	)
	(footprint ""
		(layer "F.Cu")
		(at 27.910028 -412.090108)
		(property "Reference" "J3"
			(at 26.184352 2.518918 90)
			(unlocked yes)
			(layer "F.SilkS")
			(effects
				(font
					(size 2.032 1.524)
					(thickness 0.1524)
				)
				(justify left)
			)
		)
		(property "Value" ""
			(at 0 0 0)
			(layer "F.Fab")
			(effects
				(font
					(size 1.27 1.27)
				)
			)
		)
		(duplicate_pad_numbers_are_jumpers no)
		(pad "N2_9" thru_hole circle
			(at 17.599914 27.29992 180)
			(size 0.906272 0.906272)
			(drill 0.499872)
			(layers "*.Cu" "*.Mask")
			(remove_unused_layers no)
			(net "GND")
			(clearance 0.0508)
			(thermal_gap 0.0508)
		)
		(pad "N10" thru_hole circle
			(at 19.800062 27.500072 180)
			(size 0.71628 0.71628)
			(drill 0.30988)
			(layers "*.Cu" "*.Mask")
			(remove_unused_layers no)
			(net "CLK_100M_DB2000QL_GPU_REF1_R_DN")
			(clearance 0.0508)
			(thermal_gap 0.0508)
		)
		(pad "O9" thru_hole circle
			(at 17.599914 28.599892 180)
			(size 0.71628 0.71628)
			(drill 0.30988)
			(layers "*.Cu" "*.Mask")
			(remove_unused_layers no)
			(net "CLK_100M_DB2000QL_GPU_REF0_R_DN")
			(clearance 0.0508)
			(thermal_gap 0.0508)
		)
		(pad "O10" thru_hole circle
			(at 19.800062 28.800044 180)
			(size 0.71628 0.71628)
			(drill 0.30988)
			(layers "*.Cu" "*.Mask")
			(remove_unused_layers no)
			(net "CLK_100M_DB2000QL_GPU_REF1_R_DP")
			(clearance 0.0508)
			(thermal_gap 0.0508)
		)
		(pad "P2" thru_hole circle
			(at 2.199894 30.100016 180)
			(size 0.906272 0.906272)
			(drill 0.499872)
			(layers "*.Cu" "*.Mask")
			(remove_unused_layers no)
			(net "GND")
			(clearance 0.0508)
			(thermal_gap 0.0508)
		)
		(pad "P4" thru_hole circle
			(at 6.599936 30.100016 180)
			(size 0.906272 0.906272)
			(drill 0.499872)
			(layers "*.Cu" "*.Mask")
			(remove_unused_layers no)
			(net "GND")
			(clearance 0.0508)
			(thermal_gap 0.0508)
		)
		(pad "P6" thru_hole circle
			(at 10.999978 30.100016 180)
			(size 0.906272 0.906272)
			(drill 0.499872)
			(layers "*.Cu" "*.Mask")
			(remove_unused_layers no)
			(net "GND")
			(clearance 0.0508)
			(thermal_gap 0.0508)
		)
		(pad "P8" thru_hole circle
			(at 15.40002 30.100016 180)
			(size 0.906272 0.906272)
			(drill 0.499872)
			(layers "*.Cu" "*.Mask")
			(remove_unused_layers no)
			(net "GND")
			(clearance 0.0508)
			(thermal_gap 0.0508)
		)
		(pad "P9" thru_hole circle
			(at 17.599914 29.900118 180)
			(size 0.71628 0.71628)
			(drill 0.30988)
			(layers "*.Cu" "*.Mask")
			(remove_unused_layers no)
			(net "CLK_100M_DB2000QL_GPU_REF0_R_DP")
			(clearance 0.0508)
			(thermal_gap 0.0508)
		)
		(pad "P10" thru_hole circle
			(at 19.800062 30.100016 180)
			(size 0.906272 0.906272)
			(drill 0.499872)
			(layers "*.Cu" "*.Mask")
			(remove_unused_layers no)
			(net "GND")
			(clearance 0.0508)
			(thermal_gap 0.0508)
		)
		(pad "Q1" thru_hole circle
			(at 0 31.20009 180)
			(size 0.906272 0.906272)
			(drill 0.499872)
			(layers "*.Cu" "*.Mask")
			(remove_unused_layers no)
			(net "GND")
			(clearance 0.0508)
			(thermal_gap 0.0508)
		)
		(pad "Q3" thru_hole circle
			(at 4.400042 31.20009 180)
			(size 0.906272 0.906272)
			(drill 0.499872)
			(layers "*.Cu" "*.Mask")
			(remove_unused_layers no)
			(net "GND")
			(clearance 0.0508)
			(thermal_gap 0.0508)
		)
		(pad "Q5" thru_hole circle
			(at 8.800084 31.20009 180)
			(size 0.906272 0.906272)
			(drill 0.499872)
			(layers "*.Cu" "*.Mask")
			(remove_unused_layers no)
			(net "GND")
			(clearance 0.0508)
			(thermal_gap 0.0508)
		)
		(pad "Q7" thru_hole circle
			(at 13.199872 31.20009 180)
			(size 0.906272 0.906272)
			(drill 0.499872)
			(layers "*.Cu" "*.Mask")
			(remove_unused_layers no)
			(net "GND")
			(clearance 0.0508)
			(thermal_gap 0.0508)
		)
		(pad "Q9" thru_hole circle
			(at 17.599914 31.20009 180)
			(size 0.906272 0.906272)
			(drill 0.499872)
			(layers "*.Cu" "*.Mask")
			(remove_unused_layers no)
			(net "GND")
			(clearance 0.0508)
			(thermal_gap 0.0508)
		)
		(pad "Q10" thru_hole circle
			(at 19.800062 31.399988 180)
			(size 0.71628 0.71628)
			(drill 0.30988)
			(layers "*.Cu" "*.Mask")
			(remove_unused_layers no)
			(net "SMB_GPU_1_R_SCL")
			(clearance 0.0508)
			(thermal_gap 0.0508)
		)
		(pad "R9" thru_hole circle
			(at 17.599914 32.500062 180)
			(size 0.71628 0.71628)
			(drill 0.30988)
			(layers "*.Cu" "*.Mask")
			(remove_unused_layers no)
			(net "SMB_GPU_2_R_SCL")
			(clearance 0.0508)
			(thermal_gap 0.0508)
		)
		(pad "R10" thru_hole circle
			(at 19.800062 32.69996 180)
			(size 0.71628 0.71628)
			(drill 0.30988)
			(layers "*.Cu" "*.Mask")
			(remove_unused_layers no)
			(net "SMB_GPU_1_R_SDA")
			(clearance 0.0508)
			(thermal_gap 0.0508)
		)
		(pad "S2" thru_hole circle
			(at 2.199894 33.999932 180)
			(size 0.906272 0.906272)
			(drill 0.499872)
			(layers "*.Cu" "*.Mask")
			(remove_unused_layers no)
			(net "GND")
			(clearance 0.0508)
			(thermal_gap 0.0508)
		)
		(pad "S4" thru_hole circle
			(at 6.599936 33.999932 180)
			(size 0.906272 0.906272)
			(drill 0.499872)
			(layers "*.Cu" "*.Mask")
			(remove_unused_layers no)
			(net "GND")
			(clearance 0.0508)
			(thermal_gap 0.0508)
		)
		(pad "S6" thru_hole circle
			(at 10.999978 33.999932 180)
			(size 0.906272 0.906272)
			(drill 0.499872)
			(layers "*.Cu" "*.Mask")
			(remove_unused_layers no)
			(net "GND")
			(clearance 0.0508)
			(thermal_gap 0.0508)
		)
		(pad "S8" thru_hole circle
			(at 15.40002 33.999932 180)
			(size 0.906272 0.906272)
			(drill 0.499872)
			(layers "*.Cu" "*.Mask")
			(remove_unused_layers no)
			(net "GND")
			(clearance 0.0508)
			(thermal_gap 0.0508)
		)
		(pad "S9" thru_hole circle
			(at 17.599914 33.800034 180)
			(size 0.71628 0.71628)
			(drill 0.30988)
			(layers "*.Cu" "*.Mask")
			(remove_unused_layers no)
			(net "SMB_GPU_2_R_SDA")
			(clearance 0.0508)
			(thermal_gap 0.0508)
		)
		(pad "S10" thru_hole circle
			(at 19.800062 33.999932 180)
			(size 0.906272 0.906272)
			(drill 0.499872)
			(layers "*.Cu" "*.Mask")
			(remove_unused_layers no)
			(net "GND")
			(clearance 0.0508)
			(thermal_gap 0.0508)
		)
		(pad "T1" thru_hole circle
			(at 0 35.100006 180)
			(size 0.906272 0.906272)
			(drill 0.499872)
			(layers "*.Cu" "*.Mask")
			(remove_unused_layers no)
			(net "GND")
			(clearance 0.0508)
			(thermal_gap 0.0508)
		)
		(pad "T3" thru_hole circle
			(at 4.400042 35.100006 180)
			(size 0.906272 0.906272)
			(drill 0.499872)
			(layers "*.Cu" "*.Mask")
			(remove_unused_layers no)
			(net "GND")
			(clearance 0.0508)
			(thermal_gap 0.0508)
		)
		(pad "T5" thru_hole circle
			(at 8.800084 35.100006 180)
			(size 0.906272 0.906272)
			(drill 0.499872)
			(layers "*.Cu" "*.Mask")
			(remove_unused_layers no)
			(net "GND")
			(clearance 0.0508)
			(thermal_gap 0.0508)
		)
		(pad "T7" thru_hole circle
			(at 13.199872 35.100006 180)
			(size 0.906272 0.906272)
			(drill 0.499872)
			(layers "*.Cu" "*.Mask")
			(remove_unused_layers no)
			(net "GND")
			(clearance 0.0508)
			(thermal_gap 0.0508)
		)
		(pad "T9" thru_hole circle
			(at 17.599914 35.100006 180)
			(size 0.906272 0.906272)
			(drill 0.499872)
			(layers "*.Cu" "*.Mask")
			(remove_unused_layers no)
			(net "GND")
			(clearance 0.0508)
			(thermal_gap 0.0508)
		)
		(pad "V2" thru_hole circle
			(at 2.199894 37.900102 180)
			(size 0.906272 0.906272)
			(drill 0.499872)
			(layers "*.Cu" "*.Mask")
			(remove_unused_layers no)
			(net "GND")
			(clearance 0.0508)
			(thermal_gap 0.0508)
		)
		(pad "V4" thru_hole circle
			(at 6.599936 37.900102 180)
			(size 0.906272 0.906272)
			(drill 0.499872)
			(layers "*.Cu" "*.Mask")
			(remove_unused_layers no)
			(net "GND")
			(clearance 0.0508)
			(thermal_gap 0.0508)
		)
		(pad "V6" thru_hole circle
			(at 10.999978 37.900102 180)
			(size 0.906272 0.906272)
			(drill 0.499872)
			(layers "*.Cu" "*.Mask")
			(remove_unused_layers no)
			(net "GND")
			(clearance 0.0508)
			(thermal_gap 0.0508)
		)
		(pad "V8" thru_hole circle
			(at 15.40002 37.900102 180)
			(size 0.906272 0.906272)
			(drill 0.499872)
			(layers "*.Cu" "*.Mask")
			(remove_unused_layers no)
			(net "GND")
			(clearance 0.0508)
			(thermal_gap 0.0508)
		)
		(pad "V10" thru_hole circle
			(at 19.800062 37.900102 180)
			(size 0.906272 0.906272)
			(drill 0.499872)
			(layers "*.Cu" "*.Mask")
			(remove_unused_layers no)
			(net "GND")
			(clearance 0.0508)
			(thermal_gap 0.0508)
		)
		(pad "W1" thru_hole circle
			(at 0 38.999922 180)
			(size 0.906272 0.906272)
			(drill 0.499872)
			(layers "*.Cu" "*.Mask")
			(remove_unused_layers no)
			(net "GND")
			(clearance 0.0508)
			(thermal_gap 0.0508)
		)
		(pad "W3" thru_hole circle
			(at 4.400042 38.999922 180)
			(size 0.906272 0.906272)
			(drill 0.499872)
			(layers "*.Cu" "*.Mask")
			(remove_unused_layers no)
			(net "GND")
			(clearance 0.0508)
			(thermal_gap 0.0508)
		)
		(pad "W5" thru_hole circle
			(at 8.800084 38.999922 180)
			(size 0.906272 0.906272)
			(drill 0.499872)
			(layers "*.Cu" "*.Mask")
			(remove_unused_layers no)
			(net "GND")
			(clearance 0.0508)
			(thermal_gap 0.0508)
		)
		(pad "W7" thru_hole circle
			(at 13.199872 38.999922 180)
			(size 0.906272 0.906272)
			(drill 0.499872)
			(layers "*.Cu" "*.Mask")
			(remove_unused_layers no)
			(net "GND")
			(clearance 0.0508)
			(thermal_gap 0.0508)
		)
		(pad "W9" thru_hole circle
			(at 17.599914 38.999922 180)
			(size 0.906272 0.906272)
			(drill 0.499872)
			(layers "*.Cu" "*.Mask")
			(remove_unused_layers no)
			(net "GND")
			(clearance 0.0508)
			(thermal_gap 0.0508)
		)
		(pad "Y2" thru_hole circle
			(at 2.199894 41.800018 180)
			(size 0.906272 0.906272)
			(drill 0.499872)
			(layers "*.Cu" "*.Mask")
			(remove_unused_layers no)
			(net "GND")
			(clearance 0.0508)
			(thermal_gap 0.0508)
		)
		(pad "Y4" thru_hole circle
			(at 6.599936 41.800018 180)
			(size 0.906272 0.906272)
			(drill 0.499872)
			(layers "*.Cu" "*.Mask")
			(remove_unused_layers no)
			(net "GND")
			(clearance 0.0508)
			(thermal_gap 0.0508)
		)
		(pad "Y6" thru_hole circle
			(at 10.999978 41.800018 180)
			(size 0.906272 0.906272)
			(drill 0.499872)
			(layers "*.Cu" "*.Mask")
			(remove_unused_layers no)
			(net "GND")
			(clearance 0.0508)
			(thermal_gap 0.0508)
		)
		(pad "Y8" thru_hole circle
			(at 15.40002 41.800018 180)
			(size 0.906272 0.906272)
			(drill 0.499872)
			(layers "*.Cu" "*.Mask")
			(remove_unused_layers no)
			(net "GND")
			(clearance 0.0508)
			(thermal_gap 0.0508)
		)
		(pad "Y10" thru_hole circle
			(at 19.800062 41.800018 180)
			(size 0.906272 0.906272)
			(drill 0.499872)
			(layers "*.Cu" "*.Mask")
			(remove_unused_layers no)
			(net "GND")
			(clearance 0.0508)
			(thermal_gap 0.0508)
		)
		(pad "Z1" thru_hole circle
			(at 0 42.900092 180)
			(size 0.906272 0.906272)
			(drill 0.499872)
			(layers "*.Cu" "*.Mask")
			(remove_unused_layers no)
			(net "GND")
			(clearance 0.0508)
			(thermal_gap 0.0508)
		)
		(pad "Z2" thru_hole circle
			(at 2.199894 43.09999 180)
			(size 0.71628 0.71628)
			(drill 0.30988)
			(layers "*.Cu" "*.Mask")
			(remove_unused_layers no)
			(net "PRSNT_GPU_D_N")
			(clearance 0.0508)
			(thermal_gap 0.0508)
		)
		(pad "Z3" thru_hole circle
			(at 4.400042 42.900092 180)
			(size 0.906272 0.906272)
			(drill 0.499872)
			(layers "*.Cu" "*.Mask")
			(remove_unused_layers no)
			(net "GND")
			(clearance 0.0508)
			(thermal_gap 0.0508)
		)
		(pad "Z4" thru_hole circle
			(at 6.599936 43.09999 180)
			(size 0.71628 0.71628)
			(drill 0.30988)
			(layers "*.Cu" "*.Mask")
			(remove_unused_layers no)
			(net "GPU_BASE_PWR_EN_R")
			(clearance 0.0508)
			(thermal_gap 0.0508)
		)
		(pad "Z5" thru_hole circle
			(at 8.800084 42.900092 180)
			(size 0.906272 0.906272)
			(drill 0.499872)
			(layers "*.Cu" "*.Mask")
			(remove_unused_layers no)
			(net "GND")
			(clearance 0.0508)
			(thermal_gap 0.0508)
		)
		(pad "Z6" thru_hole circle
			(at 10.999978 43.09999 180)
			(size 0.71628 0.71628)
			(drill 0.30988)
			(layers "*.Cu" "*.Mask")
			(remove_unused_layers no)
			(net "GPU_BASE_PWR_GD")
			(clearance 0.0508)
			(thermal_gap 0.0508)
		)
		(pad "Z7" thru_hole circle
			(at 13.199872 42.900092 180)
			(size 0.906272 0.906272)
			(drill 0.499872)
			(layers "*.Cu" "*.Mask")
			(remove_unused_layers no)
			(net "GND")
			(clearance 0.0508)
			(thermal_gap 0.0508)
		)
		(pad "Z8" thru_hole circle
			(at 15.40002 43.09999 180)
			(size 0.71628 0.71628)
			(drill 0.30988)
			(layers "*.Cu" "*.Mask")
			(remove_unused_layers no)
			(net "GPU_BASE_ID1_R")
			(clearance 0.0508)
			(thermal_gap 0.0508)
		)
		(pad "Z9" thru_hole circle
			(at 17.599914 42.900092 180)
			(size 0.906272 0.906272)
			(drill 0.499872)
			(layers "*.Cu" "*.Mask")
			(remove_unused_layers no)
			(net "GND")
			(clearance 0.0508)
			(thermal_gap 0.0508)
		)
		(pad "Z10" thru_hole circle
			(at 19.800062 43.09999 180)
			(size 0.71628 0.71628)
			(drill 0.30988)
			(layers "*.Cu" "*.Mask")
			(remove_unused_layers no)
			(net "RST_GPU_PERST_0_BUF_R_N")
			(clearance 0.0508)
			(thermal_gap 0.0508)
		)
	)
)
